# S9S_MB_2U (Grand Teton) — schematic netlist excerpt (pin names and nets, part order shuffled) for the footprints in the layout excerpt that follows; sources: Cadence DE-HDL packaged netlist, KiCad conversion of 03242023_DA0F0TMBIJ0_F0T_Motherboard_J_brd_V01_OCP.brd

PC636  Q_CAP  100NF 50V 10% X7R  pkg C0402  page 279 : A = SW_PVCCD_HV_CPU0_BOOT1_R ; B = SW_PVCCD_HV_CPU0_BOOTR1
PR92  Q_RES  88.7K 1% CHIP  pkg 0402LF  page 258 : A = P5V_AUX_FB ; B = P5V_AUX

(kicad_pcb
	(version 20260206)
	(generator "pcbnew")
	(generator_version "10.0")
	(general
		(thickness 1.6)
		(legacy_teardrops no)
	)
	(paper "A4")
	(title_block
		(title "03242023_DA0F0TMBIJ0_F0T_Motherboard_J_brd_V01_OCP.brd")
		(comment 1 "Grand Teton / footprints 1581-1582 of 6105")
	)
	(layers
		(0 "F.Cu" signal "TOP")
		(4 "In1.Cu" signal "GND")
		(6 "In2.Cu" signal "IN1")
		(8 "In3.Cu" signal "GND1")
		(10 "In4.Cu" signal "IN2")
		(12 "In5.Cu" signal "GND2")
		(14 "In6.Cu" signal "IN3")
		(16 "In7.Cu" signal "GND3")
		(18 "In8.Cu" signal "VCC")
		(20 "In9.Cu" signal "VCC1")
		(22 "In10.Cu" signal "GND4")
		(24 "In11.Cu" signal "IN4")
		(26 "In12.Cu" signal "GND5")
		(28 "In13.Cu" signal "IN5")
		(30 "In14.Cu" signal "GND6")
		(32 "In15.Cu" signal "IN6")
		(34 "In16.Cu" signal "GND7")
		(2 "B.Cu" signal "BOTTOM")
		(9 "F.Adhes" user "F.Adhesive")
		(11 "B.Adhes" user "B.Adhesive")
		(13 "F.Paste" user "Package Geometry/Pastemask Top")
		(15 "B.Paste" user "Package Geometry/Pastemask Bottom")
		(5 "F.SilkS" user "Ref Des/Silkscreen Top")
		(7 "B.SilkS" user "Ref Des/Silkscreen Bottom")
		(1 "F.Mask" user "Board Geometry/Soldermask Top")
		(3 "B.Mask" user "Board Geometry/Soldermask Bottom")
		(17 "Dwgs.User" user "User.Drawings")
		(19 "Cmts.User" user "User.Comments")
		(21 "Eco1.User" user "User.Eco1")
		(23 "Eco2.User" user "User.Eco2")
		(25 "Edge.Cuts" user "Board Geometry/Outline")
		(27 "Margin" user)
		(31 "F.CrtYd" user "Package Geometry/Place Bound Top")
		(29 "B.CrtYd" user "Package Geometry/Place Bound Bottom")
		(35 "F.Fab" user "Ref Des/Assembly Top")
		(33 "B.Fab" user "Ref Des/Assembly Bottom")
	)
	(footprint ""
		(layer "F.Cu")
		(at 459.267814 -380.572772)
		(property "Reference" "PR92"
			(at 0 0 0)
			(layer "F.SilkS")
			(hide yes)
			(effects
				(font
					(size 1.27 1.27)
				)
			)
		)
		(property "Value" ""
			(at 0 0 0)
			(layer "F.Fab")
			(effects
				(font
					(size 1.27 1.27)
				)
			)
		)
		(duplicate_pad_numbers_are_jumpers no)
		(fp_line
			(start -0.7874 -0.4064)
			(end 0.7874 -0.4064)
			(stroke
				(width 0.1524)
				(type default)
			)
			(layer "F.SilkS")
		)
		(fp_line
			(start -0.7874 0.4064)
			(end -0.7874 -0.4064)
			(stroke
				(width 0.1524)
				(type default)
			)
			(layer "F.SilkS")
		)
		(fp_line
			(start 0.7874 -0.4064)
			(end 0.7874 0.4064)
			(stroke
				(width 0.1524)
				(type default)
			)
			(layer "F.SilkS")
		)
		(fp_line
			(start 0.7874 0.4064)
			(end -0.7874 0.4064)
			(stroke
				(width 0.1524)
				(type default)
			)
			(layer "F.SilkS")
		)
		(fp_line
			(start -0.67945 -0.305054)
			(end -0.12065 -0.305054)
			(stroke
				(width 0.1)
				(type default)
			)
			(layer "F.Fab")
		)
		(fp_line
			(start -0.67945 0.3048)
			(end -0.67945 -0.305054)
			(stroke
				(width 0.1)
				(type default)
			)
			(layer "F.Fab")
		)
		(fp_line
			(start -0.12065 -0.305054)
			(end -0.12065 -0.2794)
			(stroke
				(width 0.1)
				(type default)
			)
			(layer "F.Fab")
		)
		(fp_line
			(start -0.12065 -0.2794)
			(end 0.12065 -0.2794)
			(stroke
				(width 0.1)
				(type default)
			)
			(layer "F.Fab")
		)
		(fp_line
			(start -0.12065 0.2794)
			(end -0.12065 0.3048)
			(stroke
				(width 0.1)
				(type default)
			)
			(layer "F.Fab")
		)
		(fp_line
			(start -0.12065 0.3048)
			(end -0.67945 0.3048)
			(stroke
				(width 0.1)
				(type default)
			)
			(layer "F.Fab")
		)
		(fp_line
			(start 0.120396 0.2794)
			(end -0.12065 0.2794)
			(stroke
				(width 0.1)
				(type default)
			)
			(layer "F.Fab")
		)
		(fp_line
			(start 0.120396 0.3048)
			(end 0.120396 0.2794)
			(stroke
				(width 0.1)
				(type default)
			)
			(layer "F.Fab")
		)
		(fp_line
			(start 0.12065 -0.3048)
			(end 0.67945 -0.3048)
			(stroke
				(width 0.1)
				(type default)
			)
			(layer "F.Fab")
		)
		(fp_line
			(start 0.12065 -0.2794)
			(end 0.12065 -0.3048)
			(stroke
				(width 0.1)
				(type default)
			)
			(layer "F.Fab")
		)
		(fp_line
			(start 0.67945 -0.3048)
			(end 0.67945 0.3048)
			(stroke
				(width 0.1)
				(type default)
			)
			(layer "F.Fab")
		)
		(fp_line
			(start 0.67945 0.3048)
			(end 0.120396 0.3048)
			(stroke
				(width 0.1)
				(type default)
			)
			(layer "F.Fab")
		)
		(pad "1" smd circle
			(at -0.40005 0)
			(size 0 0)
			(layers "F.Cu" "F.Mask" "F.Paste")
			(net "P5V_AUX_FB")
		)
		(pad "2" smd circle
			(at 0.40005 0)
			(size 0 0)
			(layers "F.Cu" "F.Mask" "F.Paste")
			(net "P5V_AUX")
		)
	)
	(footprint ""
		(layer "F.Cu")
		(at 420.4716 -160.452562 180)
		(property "Reference" "PC636"
			(at 0 0 180)
			(layer "F.SilkS")
			(hide yes)
			(effects
				(font
					(size 1.27 1.27)
				)
			)
		)
		(property "Value" ""
			(at 0 0 180)
			(layer "F.Fab")
			(effects
				(font
					(size 1.27 1.27)
				)
			)
		)
		(duplicate_pad_numbers_are_jumpers no)
		(fp_line
			(start 0.7874 0.4064)
			(end -0.7874 0.4064)
			(stroke
				(width 0.1524)
				(type default)
			)
			(layer "F.SilkS")
		)
		(fp_line
			(start 0.7874 -0.4064)
			(end 0.7874 0.4064)
			(stroke
				(width 0.1524)
				(type default)
			)
			(layer "F.SilkS")
		)
		(fp_line
			(start -0.7874 0.4064)
			(end -0.7874 -0.4064)
			(stroke
				(width 0.1524)
				(type default)
			)
			(layer "F.SilkS")
		)
		(fp_line
			(start -0.7874 -0.4064)
			(end 0.7874 -0.4064)
			(stroke
				(width 0.1524)
				(type default)
			)
			(layer "F.SilkS")
		)
		(fp_line
			(start 0.67945 0.3048)
			(end 0.120396 0.3048)
			(stroke
				(width 0.1)
				(type default)
			)
			(layer "F.Fab")
		)
		(fp_line
			(start 0.67945 -0.3048)
			(end 0.67945 0.3048)
			(stroke
				(width 0.1)
				(type default)
			)
			(layer "F.Fab")
		)
		(fp_line
			(start 0.12065 -0.2794)
			(end 0.12065 -0.3048)
			(stroke
				(width 0.1)
				(type default)
			)
			(layer "F.Fab")
		)
		(fp_line
			(start 0.12065 -0.3048)
			(end 0.67945 -0.3048)
			(stroke
				(width 0.1)
				(type default)
			)
			(layer "F.Fab")
		)
		(fp_line
			(start 0.120396 0.3048)
			(end 0.120396 0.2794)
			(stroke
				(width 0.1)
				(type default)
			)
			(layer "F.Fab")
		)
		(fp_line
			(start 0.120396 0.2794)
			(end -0.12065 0.2794)
			(stroke
				(width 0.1)
				(type default)
			)
			(layer "F.Fab")
		)
		(fp_line
			(start -0.12065 0.3048)
			(end -0.67945 0.3048)
			(stroke
				(width 0.1)
				(type default)
			)
			(layer "F.Fab")
		)
		(fp_line
			(start -0.12065 0.2794)
			(end -0.12065 0.3048)
			(stroke
				(width 0.1)
				(type default)
			)
			(layer "F.Fab")
		)
		(fp_line
			(start -0.12065 -0.2794)
			(end 0.12065 -0.2794)
			(stroke
				(width 0.1)
				(type default)
			)
			(layer "F.Fab")
		)
		(fp_line
			(start -0.12065 -0.305054)
			(end -0.12065 -0.2794)
			(stroke
				(width 0.1)
				(type default)
			)
			(layer "F.Fab")
		)
		(fp_line
			(start -0.67945 0.3048)
			(end -0.67945 -0.305054)
			(stroke
				(width 0.1)
				(type default)
			)
			(layer "F.Fab")
		)
		(fp_line
			(start -0.67945 -0.305054)
			(end -0.12065 -0.305054)
			(stroke
				(width 0.1)
				(type default)
			)
			(layer "F.Fab")
		)
		(pad "1" smd circle
			(at -0.40005 0 180)
			(size 0 0)
			(layers "F.Cu" "F.Mask" "F.Paste")
			(net "SW_PVCCD_HV_CPU0_BOOT1_R")
		)
		(pad "2" smd circle
			(at 0.40005 0 180)
			(size 0 0)
			(layers "F.Cu" "F.Mask" "F.Paste")
			(net "SW_PVCCD_HV_CPU0_BOOTR1")
		)
	)
)
